FILE_TYPE = MACRO_DRAWING;
SET COLOR_WIRE YELLOW;
SET COLOR_PROP ORANGE;
SET COLOR_DOT WHITE;
SET COLOR_ARC YELLOW;
SET COLOR_BODY GREEN;
SET COLOR_NOTE PURPLE;
SET PROP_DISPLAY VALUE;
SET PAGE_NUMBER P185;
FORCEADD OFFPAGE..3
R 2
(-9675 2125);
FORCEPROP 2 LAST $XR1 44 
J 0
(-10014 2125);
DISPLAY 0.638298 (-10014 2125);
PAINT MONO (-10014 2125);
FORCEPROP 2 LAST $XR0 13 
J 0
(-9924 2125);
DISPLAY 0.638298 (-9924 2125);
PAINT MONO (-9924 2125);
FORCEPROP 2 LAST CDS_LIB standard
J 0
(-9675 2125);
PAINT MONO (-9675 2125);
DISPLAY INVISIBLE (-9675 2125);
FORCEPROP 1 LAST OFFPAGE TRUE
J 2
(-10000 2000);
DISPLAY 0.872340 (-10000 2000);
DISPLAY INVISIBLE (-10000 2000);
FORCEPROP 1 LAST COMMENT_BODY TRUE
J 2
(-9625 2025);
DISPLAY 0.872340 (-9625 2025);
PAINT GREEN (-9625 2025);
DISPLAY INVISIBLE (-9625 2025);
FORCEPROP 2 LAST PATH I18
J 0
(-9975 2175);
DISPLAY 1.021277 (-9975 2175);
DISPLAY INVISIBLE (-9975 2175);
FORCEADD OFFPAGE..3
R 2
(-9675 3300);
FORCEPROP 2 LAST $XR0 182 
J 0
(-9955 3300);
DISPLAY 0.638298 (-9955 3300);
PAINT MONO (-9955 3300);
FORCEPROP 2 LAST CDS_LIB standard
J 0
(-9675 3300);
PAINT MONO (-9675 3300);
DISPLAY INVISIBLE (-9675 3300);
FORCEPROP 1 LAST OFFPAGE TRUE
J 2
(-10000 3175);
DISPLAY 0.872340 (-10000 3175);
DISPLAY INVISIBLE (-10000 3175);
FORCEPROP 1 LAST COMMENT_BODY TRUE
J 2
(-9625 3200);
DISPLAY 0.872340 (-9625 3200);
PAINT GREEN (-9625 3200);
DISPLAY INVISIBLE (-9625 3200);
FORCEPROP 2 LAST PATH I19
J 0
(-9975 3350);
DISPLAY 1.021277 (-9975 3350);
DISPLAY INVISIBLE (-9975 3350);
FORCEADD OFFPAGE..3
R 2
(-9650 4625);
FORCEPROP 2 LAST $XR0 240 
J 0
(-9930 4625);
DISPLAY 0.638298 (-9930 4625);
PAINT MONO (-9930 4625);
FORCEPROP 2 LAST CDS_LIB standard
J 0
(-9650 4625);
PAINT MONO (-9650 4625);
DISPLAY INVISIBLE (-9650 4625);
FORCEPROP 1 LAST OFFPAGE TRUE
J 2
(-9975 4500);
DISPLAY 0.872340 (-9975 4500);
DISPLAY INVISIBLE (-9975 4500);
FORCEPROP 1 LAST COMMENT_BODY TRUE
J 2
(-9600 4525);
DISPLAY 0.872340 (-9600 4525);
PAINT GREEN (-9600 4525);
DISPLAY INVISIBLE (-9600 4525);
FORCEPROP 2 LAST PATH I20
J 0
(-9975 4675);
DISPLAY 1.021277 (-9975 4675);
DISPLAY INVISIBLE (-9975 4675);
FORCEADD UNIVERSAL_GND..1
(-7550 2775);
FORCEPROP 3 LASTPIN (-7550 2825) SIG_NAME GND\g
J 0
(-7540 2835);
DISPLAY 0.659574 (-7540 2835);
PAINT MONO (-7540 2835);
DISPLAY INVISIBLE (-7540 2835);
FORCEPROP 2 LAST CDS_LIB logical_power
J 0
(-7550 2775);
PAINT MONO (-7550 2775);
DISPLAY INVISIBLE (-7550 2775);
FORCEPROP 1 LAST HDL_POWER GND
J 1
(-7525 2700);
DISPLAY 0.872340 (-7525 2700);
PAINT GREEN (-7525 2700);
DISPLAY INVISIBLE (-7525 2700);
FORCEPROP 1 LAST PATH I22
J 0
(-7475 2775);
DISPLAY 0.872340 (-7475 2775);
PAINT AQUA (-7475 2775);
DISPLAY INVISIBLE (-7475 2775);
FORCEPROP 2 LAST ROOM IO_SLOT
J 1
(-7775 2850);
DISPLAY 0.744681 (-7775 2850);
DISPLAY INVISIBLE (-7775 2850);
FORCEADD Q_RES..1
(-7075 3300);
FORCEPROP 1 LAST PART_NUMBER CS00002JB13
J 0
(-7200 3375);
DISPLAY 0.808511 (-7200 3375);
DISPLAY INVISIBLE (-7200 3375);
FORCEPROP 1 LAST MATERIAL CHIP
J 0
(-6775 3300);
DISPLAY 0.808511 (-6775 3300);
FORCEPROP 1 LAST VALUE 0
J 2
(-6925 3300);
DISPLAY 0.808511 (-6925 3300);
FORCEPROP 1 LAST WATTAGE 1/16W
J 2
(-6750 3450);
DISPLAY 0.808511 (-6750 3450);
FORCEPROP 1 LAST TOLERANCE 5%
J 0
(-6875 3300);
DISPLAY 0.808511 (-6875 3300);
FORCEPROP 1 LAST PACK_TYPE 0402LF
J 0
(-7200 3450);
DISPLAY 0.808511 (-7200 3450);
FORCEPROP 1 LAST $LOCATION R149
J 0
(-7350 3300);
DISPLAY 0.808511 (-7350 3300);
FORCEPROP 1 LASTPIN (-7175 3300) $PN 1
J 0
(-7163 3312);
DISPLAY 0.787234 (-7163 3312);
FORCEPROP 1 LASTPIN (-6975 3300) $PN 2
J 0
(-7013 3312);
DISPLAY 0.787234 (-7013 3312);
FORCEPROP 2 LAST CDS_LIB pure_quanta
J 0
(-7075 3300);
PAINT MONO (-7075 3300);
DISPLAY INVISIBLE (-7075 3300);
FORCEPROP 1 LAST PATH I24
J 0
(-7125 3450);
DISPLAY 0.978723 (-7125 3450);
PAINT WHITE (-7125 3450);
DISPLAY INVISIBLE (-7125 3450);
FORCEPROP 2 LAST CDS_LOCATION R149
J 0
(-6750 3500);
DISPLAY 1.021277 (-6750 3500);
DISPLAY INVISIBLE (-6750 3500);
FORCEPROP 2 LAST $SEC 1
J 0
(-6750 3500);
DISPLAY 0.680851 (-6750 3500);
PAINT MONO (-6750 3500);
DISPLAY INVISIBLE (-6750 3500);
FORCEPROP 2 LAST CDS_SEC 1
J 0
(-6750 3500);
DISPLAY 1.021277 (-6750 3500);
DISPLAY INVISIBLE (-6750 3500);
FORCEADD Q_RES..2
(-7700 3625);
FORCEPROP 1 LAST PART_NUMBER CS24752FB03
J 0
(-7660 3500);
DISPLAY 0.638298 (-7660 3500);
DISPLAY INVISIBLE (-7660 3500);
FORCEPROP 1 LAST TOLERANCE 1%
J 0
(-7655 3650);
DISPLAY 0.638298 (-7655 3650);
FORCEPROP 1 LAST MATERIAL EMPTY
J 0
(-7660 3550);
DISPLAY 0.638298 (-7660 3550);
PAINT RED (-7660 3550);
FORCEPROP 1 LAST VALUE 4.75K
J 0
(-7655 3700);
DISPLAY 0.638298 (-7655 3700);
FORCEPROP 1 LAST WATTAGE 1/16W
J 0
(-7660 3600);
DISPLAY 0.638298 (-7660 3600);
FORCEPROP 1 LAST PACK_TYPE 0402LF
J 0
(-7660 3450);
DISPLAY 0.638298 (-7660 3450);
FORCEPROP 1 LAST $LOCATION R145
J 0
(-7655 3750);
DISPLAY 0.978723 (-7655 3750);
FORCEPROP 1 LASTPIN (-7700 3725) $PN 1
J 0
(-7695 3687);
DISPLAY 0.787234 (-7695 3687);
FORCEPROP 1 LASTPIN (-7700 3525) $PN 2
J 0
(-7695 3535);
DISPLAY 0.787234 (-7695 3535);
FORCEPROP 2 LAST CDS_LIB pure_quanta
J 0
(-7700 3625);
PAINT MONO (-7700 3625);
DISPLAY INVISIBLE (-7700 3625);
FORCEPROP 1 LAST PATH I26
J 0
(-7650 3800);
DISPLAY 0.978723 (-7650 3800);
PAINT WHITE (-7650 3800);
DISPLAY INVISIBLE (-7650 3800);
FORCEPROP 2 LAST CDS_LOCATION R145
J 0
(-7650 3850);
DISPLAY 1.021277 (-7650 3850);
DISPLAY INVISIBLE (-7650 3850);
FORCEPROP 2 LAST $SEC 1
J 0
(-7650 3850);
DISPLAY 0.680851 (-7650 3850);
PAINT MONO (-7650 3850);
DISPLAY INVISIBLE (-7650 3850);
FORCEPROP 2 LAST CDS_SEC 1
J 0
(-7650 3850);
DISPLAY 1.021277 (-7650 3850);
DISPLAY INVISIBLE (-7650 3850);
FORCEADD UNIVERSAL_POWER..1
(-7700 3875);
FORCEPROP 3 LASTPIN (-7700 3825) SIG_NAME PVNN_TERM_CPU0\g
J 0
(-7690 3835);
DISPLAY 0.659574 (-7690 3835);
PAINT MONO (-7690 3835);
DISPLAY INVISIBLE (-7690 3835);
FORCEPROP 1 LAST HDL_POWER PVNN_TERM_CPU0
J 1
(-7700 3925);
DISPLAY 0.872340 (-7700 3925);
PAINT GREEN (-7700 3925);
FORCEPROP 2 LAST CDS_LIB logical_power
J 0
(-7700 3875);
PAINT MONO (-7700 3875);
DISPLAY INVISIBLE (-7700 3875);
FORCEPROP 1 LAST PATH I27
J 0
(-7650 3900);
DISPLAY 0.872340 (-7650 3900);
PAINT AQUA (-7650 3900);
DISPLAY INVISIBLE (-7650 3900);
FORCEADD UNIVERSAL_GND..1
(-7525 4100);
FORCEPROP 3 LASTPIN (-7525 4150) SIG_NAME GND\g
J 0
(-7515 4160);
DISPLAY 0.659574 (-7515 4160);
PAINT MONO (-7515 4160);
DISPLAY INVISIBLE (-7515 4160);
FORCEPROP 2 LAST CDS_LIB logical_power
J 0
(-7525 4100);
PAINT MONO (-7525 4100);
DISPLAY INVISIBLE (-7525 4100);
FORCEPROP 1 LAST HDL_POWER GND
J 1
(-7500 4025);
DISPLAY 0.872340 (-7500 4025);
PAINT GREEN (-7500 4025);
DISPLAY INVISIBLE (-7500 4025);
FORCEPROP 1 LAST PATH I28
J 0
(-7450 4100);
DISPLAY 0.872340 (-7450 4100);
PAINT AQUA (-7450 4100);
DISPLAY INVISIBLE (-7450 4100);
FORCEPROP 2 LAST ROOM IO_SLOT
J 1
(-7750 4175);
DISPLAY 0.744681 (-7750 4175);
DISPLAY INVISIBLE (-7750 4175);
FORCEADD Q_RES..2
(-7675 4950);
FORCEPROP 1 LAST PART_NUMBER CS24752FB03
J 0
(-7635 4825);
DISPLAY 0.638298 (-7635 4825);
DISPLAY INVISIBLE (-7635 4825);
FORCEPROP 1 LAST TOLERANCE 1%
J 0
(-7630 4975);
DISPLAY 0.638298 (-7630 4975);
FORCEPROP 1 LAST VALUE 4.75K
J 0
(-7630 5025);
DISPLAY 0.638298 (-7630 5025);
FORCEPROP 1 LAST MATERIAL EMPTY
J 0
(-7635 4875);
DISPLAY 0.638298 (-7635 4875);
PAINT RED (-7635 4875);
FORCEPROP 1 LAST WATTAGE 1/16W
J 0
(-7635 4925);
DISPLAY 0.638298 (-7635 4925);
FORCEPROP 1 LAST PACK_TYPE 0402LF
J 0
(-7635 4775);
DISPLAY 0.638298 (-7635 4775);
FORCEPROP 1 LAST $LOCATION R146
J 0
(-7630 5075);
DISPLAY 0.978723 (-7630 5075);
FORCEPROP 1 LASTPIN (-7675 5050) $PN 1
J 0
(-7670 5012);
DISPLAY 0.787234 (-7670 5012);
FORCEPROP 1 LASTPIN (-7675 4850) $PN 2
J 0
(-7670 4860);
DISPLAY 0.787234 (-7670 4860);
FORCEPROP 2 LAST CDS_LIB pure_quanta
J 0
(-7675 4950);
PAINT MONO (-7675 4950);
DISPLAY INVISIBLE (-7675 4950);
FORCEPROP 1 LAST PATH I30
J 0
(-7625 5125);
DISPLAY 0.978723 (-7625 5125);
PAINT WHITE (-7625 5125);
DISPLAY INVISIBLE (-7625 5125);
FORCEPROP 2 LAST CDS_LOCATION R146
J 0
(-7625 5175);
DISPLAY 1.021277 (-7625 5175);
DISPLAY INVISIBLE (-7625 5175);
FORCEPROP 2 LAST $SEC 1
J 0
(-7625 5175);
DISPLAY 0.680851 (-7625 5175);
PAINT MONO (-7625 5175);
DISPLAY INVISIBLE (-7625 5175);
FORCEPROP 2 LAST CDS_SEC 1
J 0
(-7625 5175);
DISPLAY 1.021277 (-7625 5175);
DISPLAY INVISIBLE (-7625 5175);
FORCEADD UNIVERSAL_POWER..1
(-7675 5200);
FORCEPROP 3 LASTPIN (-7675 5150) SIG_NAME PVNN_TERM_CPU0\g
J 0
(-7665 5160);
DISPLAY 0.659574 (-7665 5160);
PAINT MONO (-7665 5160);
DISPLAY INVISIBLE (-7665 5160);
FORCEPROP 1 LAST HDL_POWER PVNN_TERM_CPU0
J 1
(-7675 5250);
DISPLAY 0.872340 (-7675 5250);
PAINT GREEN (-7675 5250);
FORCEPROP 2 LAST CDS_LIB logical_power
J 0
(-7675 5200);
PAINT MONO (-7675 5200);
DISPLAY INVISIBLE (-7675 5200);
FORCEPROP 1 LAST PATH I31
J 0
(-7625 5225);
DISPLAY 0.872340 (-7625 5225);
PAINT AQUA (-7625 5225);
DISPLAY INVISIBLE (-7625 5225);
FORCEADD Q_RES..1
(-7050 4625);
FORCEPROP 1 LAST PART_NUMBER CS00002JB13
J 0
(-7175 4700);
DISPLAY 0.808511 (-7175 4700);
DISPLAY INVISIBLE (-7175 4700);
FORCEPROP 1 LAST TOLERANCE 5%
J 0
(-6850 4625);
DISPLAY 0.808511 (-6850 4625);
FORCEPROP 1 LAST MATERIAL CHIP
J 0
(-6750 4625);
DISPLAY 0.808511 (-6750 4625);
FORCEPROP 1 LAST VALUE 0
J 2
(-6900 4625);
DISPLAY 0.808511 (-6900 4625);
FORCEPROP 1 LAST WATTAGE 1/16W
J 2
(-6725 4775);
DISPLAY 0.808511 (-6725 4775);
FORCEPROP 1 LAST PACK_TYPE 0402LF
J 0
(-7175 4775);
DISPLAY 0.808511 (-7175 4775);
FORCEPROP 1 LAST $LOCATION R1297
J 0
(-7325 4625);
DISPLAY 0.808511 (-7325 4625);
FORCEPROP 1 LASTPIN (-7150 4625) $PN 1
J 0
(-7138 4637);
DISPLAY 0.787234 (-7138 4637);
FORCEPROP 1 LASTPIN (-6950 4625) $PN 2
J 0
(-6988 4637);
DISPLAY 0.787234 (-6988 4637);
FORCEPROP 2 LAST CDS_LIB pure_quanta
J 0
(-7050 4625);
PAINT MONO (-7050 4625);
DISPLAY INVISIBLE (-7050 4625);
FORCEPROP 1 LAST PATH I32
J 0
(-7100 4775);
DISPLAY 0.978723 (-7100 4775);
PAINT WHITE (-7100 4775);
DISPLAY INVISIBLE (-7100 4775);
FORCEPROP 2 LAST CDS_LOCATION R1297
J 0
(-6725 4825);
DISPLAY 1.021277 (-6725 4825);
DISPLAY INVISIBLE (-6725 4825);
FORCEPROP 2 LAST $SEC 1
J 0
(-6725 4825);
DISPLAY 0.680851 (-6725 4825);
PAINT MONO (-6725 4825);
DISPLAY INVISIBLE (-6725 4825);
FORCEPROP 2 LAST CDS_SEC 1
J 0
(-6725 4825);
DISPLAY 1.021277 (-6725 4825);
DISPLAY INVISIBLE (-6725 4825);
FORCEADD UNIVERSAL_GND..1
(-5900 3500);
FORCEPROP 3 LASTPIN (-5900 3550) SIG_NAME GND\g
J 0
(-5890 3560);
DISPLAY 0.659574 (-5890 3560);
PAINT MONO (-5890 3560);
DISPLAY INVISIBLE (-5890 3560);
FORCEPROP 2 LAST CDS_LIB logical_power
J 0
(-5900 3500);
DISPLAY INVISIBLE (-5900 3500);
FORCEPROP 1 LAST HDL_POWER GND
J 1
(-5875 3425);
DISPLAY 0.872340 (-5875 3425);
PAINT GREEN (-5875 3425);
DISPLAY INVISIBLE (-5875 3425);
FORCEPROP 1 LAST PATH I34
J 0
(-5825 3500);
DISPLAY 0.872340 (-5825 3500);
PAINT AQUA (-5825 3500);
DISPLAY INVISIBLE (-5825 3500);
FORCEPROP 2 LAST ROOM IO_SLOT
J 1
(-6125 3575);
DISPLAY 0.744681 (-6125 3575);
DISPLAY INVISIBLE (-6125 3575);
FORCEADD NC7SB3157..1
(-5450 4075);
FORCEPROP 1 LAST PART_NUMBER ALSB3157000
J 0
(-5577 4235);
DISPLAY 0.723404 (-5577 4235);
PAINT GREEN (-5577 4235);
DISPLAY INVISIBLE (-5577 4235);
FORCEPROP 1 LAST VALUE NC7SB3157P6X
J 0
(-5577 4395);
DISPLAY 0.723404 (-5577 4395);
PAINT GREEN (-5577 4395);
FORCEPROP 1 LAST MATERIAL IC
J 0
(-5577 4155);
DISPLAY 0.723404 (-5577 4155);
PAINT GREEN (-5577 4155);
FORCEPROP 2 LAST PATH I35
J 0
(-5575 4450);
DISPLAY 1.021277 (-5575 4450);
FORCEPROP 1 LAST $LOCATION U142
J 0
(-5577 4315);
DISPLAY 0.723404 (-5577 4315);
PAINT GREEN (-5577 4315);
FORCEPROP 1 LASTPIN (-5150 3975) $PN 4
J 0
(-5260 3978);
DISPLAY 0.659574 (-5260 3978);
PAINT MONO (-5260 3978);
FORCEPROP 1 LASTPIN (-5750 3975) $PN 3
J 2
(-5640 3978);
DISPLAY 0.659574 (-5640 3978);
PAINT MONO (-5640 3978);
FORCEPROP 1 LASTPIN (-5750 4075) $PN 1
J 2
(-5640 4078);
DISPLAY 0.659574 (-5640 4078);
PAINT MONO (-5640 4078);
FORCEPROP 1 LASTPIN (-5750 4025) $PN 2
J 2
(-5640 4028);
DISPLAY 0.659574 (-5640 4028);
PAINT MONO (-5640 4028);
FORCEPROP 1 LASTPIN (-5150 4075) $PN 6
J 0
(-5260 4078);
DISPLAY 0.659574 (-5260 4078);
PAINT MONO (-5260 4078);
FORCEPROP 1 LASTPIN (-5150 4025) $PN 5
J 0
(-5260 4028);
DISPLAY 0.659574 (-5260 4028);
PAINT MONO (-5260 4028);
FORCEPROP 0 LAST MANUF_PN NC7SB3157P6X
J 0
(-5625 4450);
DISPLAY 0.808511 (-5625 4450);
DISPLAY INVISIBLE (-5625 4450);
FORCEPROP 1 LAST CDS_LMAN_SYM_OUTLINE -150,50,150,-150
J 0
(-5450 4075);
DISPLAY 0.468085 (-5450 4075);
PAINT GREEN (-5450 4075);
DISPLAY INVISIBLE (-5450 4075);
FORCEPROP 2 LAST CDS_LIB pure_quanta
J 0
(-5450 4075);
DISPLAY INVISIBLE (-5450 4075);
FORCEPROP 1 LAST PACK_TYPE SMLF
J 0
(-5450 3825);
DISPLAY 0.723404 (-5450 3825);
PAINT GREEN (-5450 3825);
DISPLAY INVISIBLE (-5450 3825);
FORCEPROP 2 LAST SEC_TYPE SMLF
J 0
(-5575 4500);
DISPLAY 1.021277 (-5575 4500);
DISPLAY INVISIBLE (-5575 4500);
FORCEPROP 0 LAST CDS_LOCATION U142
J 0
(-5575 4500);
DISPLAY 1.021277 (-5575 4500);
DISPLAY INVISIBLE (-5575 4500);
FORCEPROP 0 LAST SEC 1
J 0
(-5575 4500);
DISPLAY 0.680851 (-5575 4500);
PAINT MONO (-5575 4500);
DISPLAY INVISIBLE (-5575 4500);
FORCEADD Q_CAP..1
(-4925 4475);
FORCEPROP 1 LAST PART_NUMBER CH5104KEB02
J 0
(-4875 4325);
DISPLAY 0.404255 (-4875 4325);
DISPLAY INVISIBLE (-4875 4325);
FORCEPROP 1 LAST TOLERANCE 10%
J 0
(-4875 4425);
DISPLAY 0.404255 (-4875 4425);
FORCEPROP 1 LAST PACK_TYPE C0402
J 0
(-4875 4275);
DISPLAY 0.404255 (-4875 4275);
FORCEPROP 1 LAST MATERIAL X6S
J 0
(-4875 4375);
DISPLAY 0.404255 (-4875 4375);
FORCEPROP 1 LAST VALUE 1UF
J 0
(-4875 4525);
DISPLAY 0.404255 (-4875 4525);
FORCEPROP 1 LAST VOLTAGE 25V
J 0
(-4875 4475);
DISPLAY 0.404255 (-4875 4475);
FORCEPROP 1 LAST $LOCATION C1612
J 0
(-4875 4575);
DISPLAY 0.787234 (-4875 4575);
FORCEPROP 2 LAST CDS_LIB pure_quanta
J 0
(-4925 4475);
DISPLAY INVISIBLE (-4925 4475);
FORCEPROP 1 LAST PATH I36
J 0
(-4875 4625);
DISPLAY 0.978723 (-4875 4625);
PAINT WHITE (-4875 4625);
DISPLAY INVISIBLE (-4875 4625);
FORCEPROP 0 LAST CDS_LOCATION C1612
J 0
(-4875 4625);
DISPLAY 1.021277 (-4875 4625);
DISPLAY INVISIBLE (-4875 4625);
FORCEPROP 0 LAST $SEC 1
J 0
(-4875 4625);
DISPLAY 0.680851 (-4875 4625);
PAINT MONO (-4875 4625);
DISPLAY INVISIBLE (-4875 4625);
FORCEPROP 0 LAST CDS_SEC 1
J 0
(-4875 4625);
DISPLAY 1.021277 (-4875 4625);
DISPLAY INVISIBLE (-4875 4625);
FORCEPROP 1 LASTPIN (-4925 4575) $PN 1
J 0
(-4915 4555);
DISPLAY 0.787234 (-4915 4555);
PAINT MONO (-4915 4555);
DISPLAY INVISIBLE (-4915 4555);
FORCEPROP 1 LASTPIN (-4925 4375) $PN 2
J 0
(-4915 4355);
DISPLAY 0.787234 (-4915 4355);
PAINT MONO (-4915 4355);
DISPLAY INVISIBLE (-4915 4355);
FORCEADD UNIVERSAL_POWER..1
(-5025 4750);
FORCEPROP 3 LASTPIN (-5025 4700) SIG_NAME P3V3_AUX\g
J 0
(-5015 4710);
DISPLAY 0.659574 (-5015 4710);
PAINT MONO (-5015 4710);
DISPLAY INVISIBLE (-5015 4710);
FORCEPROP 1 LAST HDL_POWER P3V3_AUX
J 1
(-5025 4800);
DISPLAY 0.872340 (-5025 4800);
PAINT GREEN (-5025 4800);
FORCEPROP 2 LAST CDS_LIB logical_power
J 0
(-5025 4750);
DISPLAY INVISIBLE (-5025 4750);
FORCEPROP 1 LAST PATH I37
J 0
(-4975 4775);
DISPLAY 0.872340 (-4975 4775);
PAINT AQUA (-4975 4775);
DISPLAY INVISIBLE (-4975 4775);
FORCEADD UNIVERSAL_GND..1
(-4925 4275);
FORCEPROP 3 LASTPIN (-4925 4325) SIG_NAME GND\g
J 0
(-4915 4335);
DISPLAY 0.659574 (-4915 4335);
PAINT MONO (-4915 4335);
DISPLAY INVISIBLE (-4915 4335);
FORCEPROP 2 LAST CDS_LIB logical_power
J 0
(-4925 4275);
DISPLAY INVISIBLE (-4925 4275);
FORCEPROP 1 LAST HDL_POWER GND
J 1
(-4900 4200);
DISPLAY 0.872340 (-4900 4200);
PAINT GREEN (-4900 4200);
DISPLAY INVISIBLE (-4900 4200);
FORCEPROP 1 LAST PATH I38
J 0
(-4850 4275);
DISPLAY 0.872340 (-4850 4275);
PAINT AQUA (-4850 4275);
DISPLAY INVISIBLE (-4850 4275);
FORCEPROP 2 LAST ROOM IO_SLOT
J 1
(-5150 4350);
DISPLAY 0.744681 (-5150 4350);
DISPLAY INVISIBLE (-5150 4350);
FORCEADD Q_RES..2
(-4625 4350);
FORCEPROP 1 LAST PART_NUMBER CS24752FB03
J 0
(-4585 4225);
DISPLAY 0.404255 (-4585 4225);
DISPLAY INVISIBLE (-4585 4225);
FORCEPROP 1 LAST MATERIAL CHIP
J 0
(-4585 4275);
DISPLAY 0.404255 (-4585 4275);
FORCEPROP 1 LAST WATTAGE 1/16W
J 0
(-4585 4325);
DISPLAY 0.404255 (-4585 4325);
FORCEPROP 1 LAST VALUE 4.75K
J 0
(-4580 4425);
DISPLAY 0.404255 (-4580 4425);
FORCEPROP 1 LAST TOLERANCE 1%
J 0
(-4580 4375);
DISPLAY 0.404255 (-4580 4375);
FORCEPROP 1 LAST PACK_TYPE 0402LF
J 0
(-4585 4175);
DISPLAY 0.404255 (-4585 4175);
FORCEPROP 1 LAST $LOCATION R2253
J 0
(-4580 4475);
DISPLAY 0.510638 (-4580 4475);
FORCEPROP 2 LAST CDS_LIB pure_quanta
J 0
(-4625 4350);
DISPLAY INVISIBLE (-4625 4350);
FORCEPROP 1 LAST PATH I39
J 0
(-4575 4525);
DISPLAY 0.978723 (-4575 4525);
PAINT WHITE (-4575 4525);
DISPLAY INVISIBLE (-4575 4525);
FORCEPROP 0 LAST CDS_LOCATION R2253
J 0
(-4575 4500);
DISPLAY 1.021277 (-4575 4500);
DISPLAY INVISIBLE (-4575 4500);
FORCEPROP 0 LAST $SEC 1
J 0
(-4575 4500);
DISPLAY 0.680851 (-4575 4500);
PAINT MONO (-4575 4500);
DISPLAY INVISIBLE (-4575 4500);
FORCEPROP 0 LAST CDS_SEC 1
J 0
(-4575 4500);
DISPLAY 1.021277 (-4575 4500);
DISPLAY INVISIBLE (-4575 4500);
FORCEPROP 1 LASTPIN (-4625 4450) $PN 1
J 0
(-4620 4412);
DISPLAY 0.787234 (-4620 4412);
PAINT MONO (-4620 4412);
DISPLAY INVISIBLE (-4620 4412);
FORCEPROP 1 LASTPIN (-4625 4250) $PN 2
J 0
(-4620 4260);
DISPLAY 0.787234 (-4620 4260);
PAINT MONO (-4620 4260);
DISPLAY INVISIBLE (-4620 4260);
FORCEADD UNIVERSAL_POWER..1
(-4625 4625);
FORCEPROP 3 LASTPIN (-4625 4575) SIG_NAME P3V3_AUX\g
J 0
(-4615 4585);
DISPLAY 0.659574 (-4615 4585);
PAINT MONO (-4615 4585);
DISPLAY INVISIBLE (-4615 4585);
FORCEPROP 1 LAST HDL_POWER P3V3_AUX
J 1
(-4625 4675);
DISPLAY 0.872340 (-4625 4675);
PAINT GREEN (-4625 4675);
FORCEPROP 2 LAST CDS_LIB logical_power
J 0
(-4625 4625);
DISPLAY INVISIBLE (-4625 4625);
FORCEPROP 1 LAST PATH I40
J 0
(-4575 4650);
DISPLAY 0.872340 (-4575 4650);
PAINT AQUA (-4575 4650);
DISPLAY INVISIBLE (-4575 4650);
FORCEADD Q_RES..1
(-3675 4075);
FORCEPROP 1 LAST PART_NUMBER CS00002JB13
J 0
(-3800 4150);
DISPLAY 0.510638 (-3800 4150);
DISPLAY INVISIBLE (-3800 4150);
FORCEPROP 1 LAST PACK_TYPE 0402LF
J 0
(-3800 4200);
DISPLAY 0.510638 (-3800 4200);
FORCEPROP 1 LAST MATERIAL CHIP
J 0
(-3425 4075);
DISPLAY 0.510638 (-3425 4075);
FORCEPROP 1 LAST TOLERANCE 5%
J 0
(-3500 4075);
DISPLAY 0.510638 (-3500 4075);
FORCEPROP 1 LAST VALUE 0
J 2
(-3525 4075);
DISPLAY 0.510638 (-3525 4075);
FORCEPROP 1 LAST WATTAGE 1/16W
J 2
(-3500 4200);
DISPLAY 0.510638 (-3500 4200);
FORCEPROP 1 LAST $LOCATION R2255
J 0
(-3925 4075);
DISPLAY 0.787234 (-3925 4075);
FORCEPROP 2 LAST CDS_LIB pure_quanta
J 0
(-3675 4075);
DISPLAY INVISIBLE (-3675 4075);
FORCEPROP 1 LAST PATH I41
J 0
(-3725 4225);
DISPLAY 0.978723 (-3725 4225);
PAINT WHITE (-3725 4225);
DISPLAY INVISIBLE (-3725 4225);
FORCEPROP 0 LAST CDS_LOCATION R2255
J 0
(-3500 4225);
DISPLAY 1.021277 (-3500 4225);
DISPLAY INVISIBLE (-3500 4225);
FORCEPROP 0 LAST $SEC 1
J 0
(-3500 4225);
DISPLAY 0.680851 (-3500 4225);
PAINT MONO (-3500 4225);
DISPLAY INVISIBLE (-3500 4225);
FORCEPROP 0 LAST CDS_SEC 1
J 0
(-3500 4225);
DISPLAY 1.021277 (-3500 4225);
DISPLAY INVISIBLE (-3500 4225);
FORCEPROP 1 LASTPIN (-3775 4075) $PN 1
J 0
(-3763 4087);
DISPLAY 0.787234 (-3763 4087);
PAINT MONO (-3763 4087);
DISPLAY INVISIBLE (-3763 4087);
FORCEPROP 1 LASTPIN (-3575 4075) $PN 2
J 0
(-3613 4087);
DISPLAY 0.787234 (-3613 4087);
PAINT MONO (-3613 4087);
DISPLAY INVISIBLE (-3613 4087);
FORCEADD Q_RES..2
(-4675 3825);
FORCEPROP 1 LAST PART_NUMBER CS41002FB09
J 0
(-4635 3700);
DISPLAY 0.404255 (-4635 3700);
DISPLAY INVISIBLE (-4635 3700);
FORCEPROP 1 LAST TOLERANCE 1%
J 0
(-4630 3850);
DISPLAY 0.404255 (-4630 3850);
FORCEPROP 1 LAST WATTAGE 1/16W
J 0
(-4635 3800);
DISPLAY 0.404255 (-4635 3800);
FORCEPROP 1 LAST MATERIAL EMPTY
J 0
(-4635 3750);
DISPLAY 0.404255 (-4635 3750);
PAINT RED (-4635 3750);
FORCEPROP 1 LAST VALUE 100K
J 0
(-4630 3900);
DISPLAY 0.404255 (-4630 3900);
FORCEPROP 1 LAST PACK_TYPE 0402LF
J 0
(-4635 3650);
DISPLAY 0.404255 (-4635 3650);
FORCEPROP 1 LAST $LOCATION R2252
J 0
(-4630 3950);
DISPLAY 0.404255 (-4630 3950);
FORCEPROP 2 LAST CDS_LIB pure_quanta
J 0
(-4675 3825);
DISPLAY INVISIBLE (-4675 3825);
FORCEPROP 1 LAST PATH I42
J 0
(-4625 4000);
DISPLAY 0.978723 (-4625 4000);
PAINT WHITE (-4625 4000);
DISPLAY INVISIBLE (-4625 4000);
FORCEPROP 0 LAST CDS_LOCATION R2252
J 0
(-4625 3975);
DISPLAY 1.021277 (-4625 3975);
DISPLAY INVISIBLE (-4625 3975);
FORCEPROP 0 LAST $SEC 1
J 0
(-4625 3975);
DISPLAY 0.680851 (-4625 3975);
PAINT MONO (-4625 3975);
DISPLAY INVISIBLE (-4625 3975);
FORCEPROP 0 LAST CDS_SEC 1
J 0
(-4625 3975);
DISPLAY 1.021277 (-4625 3975);
DISPLAY INVISIBLE (-4625 3975);
FORCEPROP 1 LASTPIN (-4675 3925) $PN 1
J 0
(-4670 3887);
DISPLAY 0.787234 (-4670 3887);
PAINT MONO (-4670 3887);
DISPLAY INVISIBLE (-4670 3887);
FORCEPROP 1 LASTPIN (-4675 3725) $PN 2
J 0
(-4670 3735);
DISPLAY 0.787234 (-4670 3735);
PAINT MONO (-4670 3735);
DISPLAY INVISIBLE (-4670 3735);
FORCEADD UNIVERSAL_GND..1
(-4675 3575);
FORCEPROP 3 LASTPIN (-4675 3625) SIG_NAME GND\g
J 0
(-4665 3635);
DISPLAY 0.659574 (-4665 3635);
PAINT MONO (-4665 3635);
DISPLAY INVISIBLE (-4665 3635);
FORCEPROP 2 LAST CDS_LIB logical_power
J 0
(-4675 3575);
DISPLAY INVISIBLE (-4675 3575);
FORCEPROP 1 LAST HDL_POWER GND
J 1
(-4650 3500);
DISPLAY 0.872340 (-4650 3500);
PAINT GREEN (-4650 3500);
DISPLAY INVISIBLE (-4650 3500);
FORCEPROP 1 LAST PATH I43
J 0
(-4600 3575);
DISPLAY 0.872340 (-4600 3575);
PAINT AQUA (-4600 3575);
DISPLAY INVISIBLE (-4600 3575);
FORCEPROP 2 LAST ROOM IO_SLOT
J 1
(-4900 3650);
DISPLAY 0.744681 (-4900 3650);
DISPLAY INVISIBLE (-4900 3650);
FORCEADD OFFPAGE..4
(-2500 4075);
FORCEPROP 2 LAST $XR0 213 
J 0
(-2314 4075);
DISPLAY 0.638298 (-2314 4075);
PAINT MONO (-2314 4075);
FORCEPROP 2 LAST CDS_LIB standard
J 0
(-2500 4075);
DISPLAY INVISIBLE (-2500 4075);
FORCEPROP 1 LAST OFFPAGE TRUE
J 0
(-2175 3950);
DISPLAY 0.872340 (-2175 3950);
DISPLAY INVISIBLE (-2175 3950);
FORCEPROP 1 LAST COMMENT_BODY TRUE
J 0
(-2525 3975);
DISPLAY 0.872340 (-2525 3975);
PAINT GREEN (-2525 3975);
DISPLAY INVISIBLE (-2525 3975);
FORCEPROP 2 LAST PATH I44
J 0
(-2300 4125);
DISPLAY 1.021277 (-2300 4125);
DISPLAY INVISIBLE (-2300 4125);
FORCEADD Q_RES..1
(-4275 2125);
FORCEPROP 1 LAST PART_NUMBER CS00002JB13
J 0
(-4400 2200);
DISPLAY 0.510638 (-4400 2200);
DISPLAY INVISIBLE (-4400 2200);
FORCEPROP 1 LAST PACK_TYPE 0402LF
J 0
(-4400 2250);
DISPLAY 0.510638 (-4400 2250);
FORCEPROP 1 LAST VALUE 0
J 2
(-4125 2125);
DISPLAY 0.510638 (-4125 2125);
FORCEPROP 1 LAST MATERIAL EMPTY
J 0
(-4025 2125);
DISPLAY 0.510638 (-4025 2125);
PAINT RED (-4025 2125);
FORCEPROP 1 LAST TOLERANCE 5%
J 0
(-4100 2125);
DISPLAY 0.510638 (-4100 2125);
FORCEPROP 1 LAST WATTAGE 1/16W
J 2
(-4100 2250);
DISPLAY 0.510638 (-4100 2250);
FORCEPROP 1 LAST $LOCATION R3064
J 0
(-4325 2175);
DISPLAY 0.978723 (-4325 2175);
FORCEPROP 1 LASTPIN (-4375 2125) $PN 1
J 0
(-4363 2137);
DISPLAY 0.787234 (-4363 2137);
PAINT MONO (-4363 2137);
FORCEPROP 1 LASTPIN (-4175 2125) $PN 2
J 0
(-4213 2137);
DISPLAY 0.787234 (-4213 2137);
PAINT MONO (-4213 2137);
FORCEPROP 2 LAST CDS_LIB pure_quanta
J 0
(-4275 2125);
DISPLAY INVISIBLE (-4275 2125);
FORCEPROP 1 LAST PATH I45
J 0
(-4325 2275);
DISPLAY 0.978723 (-4325 2275);
PAINT WHITE (-4325 2275);
DISPLAY INVISIBLE (-4325 2275);
FORCEPROP 0 LAST CDS_LOCATION R3064
J 0
(-4100 2275);
DISPLAY 1.021277 (-4100 2275);
DISPLAY INVISIBLE (-4100 2275);
FORCEPROP 0 LAST $SEC 1
J 0
(-4100 2275);
DISPLAY 0.680851 (-4100 2275);
PAINT MONO (-4100 2275);
DISPLAY INVISIBLE (-4100 2275);
FORCEPROP 0 LAST CDS_SEC 1
J 0
(-4100 2275);
DISPLAY 1.021277 (-4100 2275);
DISPLAY INVISIBLE (-4100 2275);
FORCEADD OFFPAGE..3
(-3200 2125);
FORCEPROP 2 LAST $XR0 228 
J 0
(-2986 2125);
DISPLAY 0.638298 (-2986 2125);
PAINT MONO (-2986 2125);
FORCEPROP 2 LAST CDS_LIB standard
J 2
(-3200 2125);
DISPLAY INVISIBLE (-3200 2125);
FORCEPROP 1 LAST OFFPAGE TRUE
J 0
(-2875 2000);
DISPLAY 0.872340 (-2875 2000);
DISPLAY INVISIBLE (-2875 2000);
FORCEPROP 1 LAST COMMENT_BODY TRUE
J 0
(-3250 2025);
DISPLAY 0.872340 (-3250 2025);
PAINT GREEN (-3250 2025);
DISPLAY INVISIBLE (-3250 2025);
FORCEPROP 2 LAST PATH I46
J 2
(-3250 2200);
DISPLAY 1.021277 (-3250 2200);
DISPLAY INVISIBLE (-3250 2200);
FORCEADD Q_RES..1
(-8800 3300);
FORCEPROP 1 LAST PART_NUMBER CS04992FB07
J 0
(-8950 3400);
DISPLAY 0.787234 (-8950 3400);
DISPLAY INVISIBLE (-8950 3400);
FORCEPROP 1 LAST MATERIAL CHIP
J 0
(-8375 3300);
DISPLAY 0.787234 (-8375 3300);
FORCEPROP 1 LAST VALUE 49.9
J 2
(-8500 3300);
DISPLAY 0.787234 (-8500 3300);
FORCEPROP 1 LAST TOLERANCE 1%
J 0
(-8500 3300);
DISPLAY 0.787234 (-8500 3300);
FORCEPROP 1 LAST WATTAGE 1/16W
J 2
(-8450 3475);
DISPLAY 0.787234 (-8450 3475);
FORCEPROP 1 LAST PACK_TYPE 0402LF
J 0
(-8950 3475);
DISPLAY 0.787234 (-8950 3475);
FORCEPROP 1 LAST LOCATION R143
J 0
(-9025 3300);
DISPLAY 0.638298 (-9025 3300);
FORCEPROP 1 LASTPIN (-8900 3300) $PN 1
J 0
(-8888 3312);
DISPLAY 0.787234 (-8888 3312);
PAINT MONO (-8888 3312);
FORCEPROP 1 LASTPIN (-8700 3300) $PN 2
J 0
(-8738 3312);
DISPLAY 0.787234 (-8738 3312);
PAINT MONO (-8738 3312);
FORCEPROP 2 LAST CDS_LIB pure_quanta
J 0
(-8800 3300);
DISPLAY INVISIBLE (-8800 3300);
FORCEPROP 1 LAST PATH I47
J 0
(-8850 3450);
DISPLAY 0.978723 (-8850 3450);
PAINT WHITE (-8850 3450);
DISPLAY INVISIBLE (-8850 3450);
FORCEPROP 0 LAST $SEC 1
J 0
(-8450 3525);
DISPLAY 0.680851 (-8450 3525);
PAINT MONO (-8450 3525);
DISPLAY INVISIBLE (-8450 3525);
FORCEPROP 0 LAST CDS_SEC 1
J 0
(-8450 3525);
DISPLAY 1.021277 (-8450 3525);
DISPLAY INVISIBLE (-8450 3525);
FORCEADD Q_RES..2
(-7525 4375);
FORCEPROP 1 LAST PART_NUMBER CS31002FB08
J 0
(-7485 4250);
DISPLAY 0.787234 (-7485 4250);
DISPLAY INVISIBLE (-7485 4250);
FORCEPROP 1 LAST WATTAGE 1/16W
J 0
(-7485 4350);
DISPLAY 0.787234 (-7485 4350);
FORCEPROP 1 LAST TOLERANCE 1%
J 0
(-7480 4400);
DISPLAY 0.787234 (-7480 4400);
FORCEPROP 1 LAST MATERIAL EMPTY
J 0
(-7485 4300);
DISPLAY 0.787234 (-7485 4300);
PAINT RED (-7485 4300);
FORCEPROP 1 LAST PACK_TYPE 0402LF
J 0
(-7485 4200);
DISPLAY 0.787234 (-7485 4200);
FORCEPROP 1 LAST VALUE 10K
J 0
(-7480 4450);
DISPLAY 0.787234 (-7480 4450);
FORCEPROP 1 LAST LOCATION R148
J 0
(-7480 4500);
DISPLAY 0.787234 (-7480 4500);
FORCEPROP 1 LASTPIN (-7525 4475) $PN 1
J 0
(-7520 4437);
DISPLAY 0.787234 (-7520 4437);
PAINT MONO (-7520 4437);
FORCEPROP 1 LASTPIN (-7525 4275) $PN 2
J 0
(-7520 4285);
DISPLAY 0.787234 (-7520 4285);
PAINT MONO (-7520 4285);
FORCEPROP 2 LAST CDS_LIB pure_quanta
J 0
(-7525 4375);
DISPLAY INVISIBLE (-7525 4375);
FORCEPROP 1 LAST PATH I49
J 0
(-7475 4550);
DISPLAY 0.978723 (-7475 4550);
PAINT WHITE (-7475 4550);
DISPLAY INVISIBLE (-7475 4550);
FORCEPROP 0 LAST $SEC 1
J 0
(-7475 4550);
DISPLAY 0.680851 (-7475 4550);
PAINT MONO (-7475 4550);
DISPLAY INVISIBLE (-7475 4550);
FORCEPROP 0 LAST CDS_SEC 1
J 0
(-7475 4550);
DISPLAY 1.021277 (-7475 4550);
DISPLAY INVISIBLE (-7475 4550);
FORCEADD Q_RES..2
(-7550 3050);
FORCEPROP 1 LAST PART_NUMBER CS31002FB08
J 0
(-7510 2925);
DISPLAY 0.787234 (-7510 2925);
DISPLAY INVISIBLE (-7510 2925);
FORCEPROP 1 LAST PACK_TYPE 0402LF
J 0
(-7510 2875);
DISPLAY 0.787234 (-7510 2875);
FORCEPROP 1 LAST MATERIAL CHIP
J 0
(-7510 2975);
DISPLAY 0.787234 (-7510 2975);
FORCEPROP 1 LAST WATTAGE 1/16W
J 0
(-7510 3025);
DISPLAY 0.787234 (-7510 3025);
FORCEPROP 1 LAST TOLERANCE 1%
J 0
(-7505 3075);
DISPLAY 0.787234 (-7505 3075);
FORCEPROP 1 LAST VALUE 10K
J 0
(-7505 3125);
DISPLAY 0.787234 (-7505 3125);
FORCEPROP 1 LAST LOCATION R147
J 0
(-7505 3175);
DISPLAY 0.787234 (-7505 3175);
FORCEPROP 1 LASTPIN (-7550 3150) $PN 1
J 0
(-7545 3112);
DISPLAY 0.787234 (-7545 3112);
PAINT MONO (-7545 3112);
FORCEPROP 1 LASTPIN (-7550 2950) $PN 2
J 0
(-7545 2960);
DISPLAY 0.787234 (-7545 2960);
PAINT MONO (-7545 2960);
FORCEPROP 2 LAST CDS_LIB pure_quanta
J 0
(-7550 3050);
DISPLAY INVISIBLE (-7550 3050);
FORCEPROP 1 LAST PATH I50
J 0
(-7500 3225);
DISPLAY 0.978723 (-7500 3225);
PAINT WHITE (-7500 3225);
DISPLAY INVISIBLE (-7500 3225);
FORCEPROP 0 LAST $SEC 1
J 0
(-7500 3225);
DISPLAY 0.680851 (-7500 3225);
PAINT MONO (-7500 3225);
DISPLAY INVISIBLE (-7500 3225);
FORCEPROP 0 LAST CDS_SEC 1
J 0
(-7500 3225);
DISPLAY 1.021277 (-7500 3225);
DISPLAY INVISIBLE (-7500 3225);
FORCEADD Q_RES..1
(-8800 4625);
FORCEPROP 1 LAST PART_NUMBER CS00002JB13
J 0
(-8925 4700);
DISPLAY 0.808511 (-8925 4700);
DISPLAY INVISIBLE (-8925 4700);
FORCEPROP 1 LAST WATTAGE 1/16W
J 2
(-8475 4775);
DISPLAY 0.808511 (-8475 4775);
FORCEPROP 1 LAST PACK_TYPE 0402LF
J 0
(-8925 4775);
DISPLAY 0.808511 (-8925 4775);
FORCEPROP 1 LAST VALUE 0
J 2
(-8650 4625);
DISPLAY 0.808511 (-8650 4625);
FORCEPROP 1 LAST TOLERANCE 5%
J 0
(-8600 4625);
DISPLAY 0.808511 (-8600 4625);
FORCEPROP 1 LAST MATERIAL CHIP
J 0
(-8500 4625);
DISPLAY 0.808511 (-8500 4625);
FORCEPROP 1 LAST LOCATION R144
J 0
(-9050 4625);
DISPLAY 0.978723 (-9050 4625);
FORCEPROP 1 LASTPIN (-8900 4625) $PN 1
J 0
(-8888 4637);
DISPLAY 0.787234 (-8888 4637);
PAINT MONO (-8888 4637);
FORCEPROP 1 LASTPIN (-8700 4625) $PN 2
J 0
(-8738 4637);
DISPLAY 0.787234 (-8738 4637);
PAINT MONO (-8738 4637);
FORCEPROP 2 LAST CDS_LIB pure_quanta
J 0
(-8800 4625);
DISPLAY INVISIBLE (-8800 4625);
FORCEPROP 1 LAST PATH I51
J 0
(-8850 4775);
DISPLAY 0.978723 (-8850 4775);
PAINT WHITE (-8850 4775);
DISPLAY INVISIBLE (-8850 4775);
FORCEPROP 0 LAST $SEC 1
J 0
(-8475 4825);
DISPLAY 0.680851 (-8475 4825);
PAINT MONO (-8475 4825);
DISPLAY INVISIBLE (-8475 4825);
FORCEPROP 0 LAST CDS_SEC 1
J 0
(-8475 4825);
DISPLAY 1.021277 (-8475 4825);
DISPLAY INVISIBLE (-8475 4825);
FORCEADD QUANTA_TITLE_BLOCK_C..1
(-1325 25);
FORCEPROP 0 LAST CDS_CON_LAST_MODIFIED Fri Aug 25 14:03:11 2023
J 0
(-3210 40);
PAINT MONO (-3210 40);
DISPLAY INVISIBLE (-3210 40);
FORCEPROP 2 LAST CUSTOM_TXT_CDS <XR_PAGE_TITLE>
J 0
(-9215 5275);
DISPLAY 0.638298 (-9215 5275);
PAINT PINK (-9215 5275);
DISPLAY INVISIBLE (-9215 5275);
FORCEPROP 2 LAST CUSTOM_TXT_CDS <CON_LAST_MODIFIED>
J 0
(-3210 40);
DISPLAY 0.978723 (-3210 40);
FORCEPROP 2 LAST CUSTOM_TXT_CDS <NAME_2>
J 0
(-4500 75);
FORCEPROP 2 LAST CUSTOM_TXT_CDS <NAME_1>
J 0
(-4500 200);
FORCEPROP 2 LAST CUSTOM_TXT_CDS <Q_NUMBER>
J 0
(-2728 128);
DISPLAY 1.212766 (-2728 128);
FORCEPROP 2 LAST CUSTOM_TXT_CDS <Q_PROJ>
J 0
(-3707 127);
DISPLAY 1.212766 (-3707 127);
FORCEPROP 2 LAST CUSTOM_TXT_CDS <Q_REV>
J 0
(-1509 128);
DISPLAY 1.212766 (-1509 128);
FORCEPROP 2 LAST CUSTOM_TXT_CDS <CON_PAGE_NUM> OF <CON_TOTAL_PAGES>
J 0
(-1771 43);
DISPLAY 0.978723 (-1771 43);
FORCEPROP 1 LAST Q_TITLE PCH - PECI
J 0
(-10591 51);
DISPLAY 2.446809 (-10591 51);
PAINT GREEN (-10591 51);
FORCEPROP 1 LAST Q_DEPT 
J 1
(-5088 74);
DISPLAY 1.957447 (-5088 74);
PAINT GREEN (-5088 74);
FORCEPROP 2 LAST CDS_XR_PAGE_TITLE CR-197 : @S9S_MB_2U_LIB.S9S_MB_2U(SCH_1):PAGE197
J 0
(-9215 5275);
DISPLAY 0.638298 (-9215 5275);
PAINT PINK (-9215 5275);
DISPLAY INVISIBLE (-9215 5275);
FORCEPROP 1 LAST COMMENT_BODY TRUE
J 0
(-1313 12);
DISPLAY 0.978723 (-1313 12);
PAINT GREEN (-1313 12);
DISPLAY INVISIBLE (-1313 12);
FORCEPROP 2 LAST CDS_LIB pure_quanta
J 0
(-1325 25);
PAINT MONO (-1325 25);
DISPLAY INVISIBLE (-1325 25);
FORCEPROP 1 LAST CDS_LMAN_SYM_OUTLINE -9475,6775,100,-125
J 0
(-1325 25);
DISPLAY 0.468085 (-1325 25);
PAINT GREEN (-1325 25);
DISPLAY INVISIBLE (-1325 25);
FORCEPROP 2 LAST PAGE_BORDER TRUE
J 0
(-9215 5275);
DISPLAY 0.638298 (-9215 5275);
PAINT PINK (-9215 5275);
DISPLAY INVISIBLE (-9215 5275);
FORCEADD DNS..2
(-7525 4350);
PAINT RED (-7525 4350);
FORCEPROP 2 LAST CDS_LIB mstr_misc
J 0
(-7525 4350);
DISPLAY INVISIBLE (-7525 4350);
FORCEPROP 1 LAST COMMENT_BODY TRUE
J 0
(-7525 4350);
DISPLAY INVISIBLE (-7525 4350);
FORCEADD DNS..2
(-7695 3620);
PAINT RED (-7695 3620);
FORCEPROP 2 LAST CDS_LIB mstr_misc
J 0
(-7695 3620);
PAINT MONO (-7695 3620);
DISPLAY INVISIBLE (-7695 3620);
FORCEPROP 1 LAST COMMENT_BODY TRUE
J 0
(-7695 3620);
DISPLAY INVISIBLE (-7695 3620);
FORCEADD DESIGN_NOTE..1
(-6925 5350);
FORCEPROP 0 LAST S2 PD ON SCM B/D
J 0
(-7125 5075);
DISPLAY 1.021277 (-7125 5075);
PAINT SKYBLUE (-7125 5075);
FORCEPROP 0 LAST S1 R148 IS FOR N-1 SUPPORT
J 0
(-7125 5175);
DISPLAY 1.021277 (-7125 5175);
PAINT SKYBLUE (-7125 5175);
FORCEPROP 2 LAST CDS_LIB logical_power
J 0
(-6925 5350);
DISPLAY INVISIBLE (-6925 5350);
FORCEPROP 1 LAST COMMENT_BODY TRUE
J 0
(-6900 5450);
DISPLAY 0.978723 (-6900 5450);
DISPLAY INVISIBLE (-6900 5450);
FORCEADD DNS..2
(-4250 2125);
PAINT RED (-4250 2125);
FORCEPROP 2 LAST CDS_LIB mstr_misc
J 0
(-4250 2125);
DISPLAY INVISIBLE (-4250 2125);
FORCEPROP 1 LAST COMMENT_BODY TRUE
J 0
(-4250 2125);
DISPLAY INVISIBLE (-4250 2125);
FORCEADD DNS..2
(-4675 3800);
PAINT RED (-4675 3800);
FORCEPROP 2 LAST CDS_LIB mstr_misc
J 0
(-4675 3800);
DISPLAY INVISIBLE (-4675 3800);
FORCEPROP 1 LAST COMMENT_BODY TRUE
J 0
(-4675 3800);
DISPLAY INVISIBLE (-4675 3800);
FORCEADD DNS..2
(-7670 4945);
PAINT RED (-7670 4945);
FORCEPROP 2 LAST CDS_LIB mstr_misc
J 0
(-7670 4945);
PAINT MONO (-7670 4945);
DISPLAY INVISIBLE (-7670 4945);
FORCEPROP 1 LAST COMMENT_BODY TRUE
J 0
(-7670 4945);
DISPLAY INVISIBLE (-7670 4945);
FORCEADD DESIGN_NOTE..1
(-3375 3800);
FORCEPROP 0 LAST S1 FM_PECI_MUX_SEL_N IS L : PCH TO CPU
J 0
(-3575 3475);
DISPLAY 1.021277 (-3575 3475);
PAINT SKYBLUE (-3575 3475);
FORCEPROP 0 LAST S2 FM_PECI_MUX_SEL_N IS H : BMC TO CPU
J 0
(-3575 3575);
DISPLAY 1.021277 (-3575 3575);
PAINT SKYBLUE (-3575 3575);
FORCEPROP 2 LAST CDS_LIB logical_power
J 0
(-3375 3800);
DISPLAY INVISIBLE (-3375 3800);
FORCEPROP 1 LAST COMMENT_BODY TRUE
J 0
(-3350 3900);
DISPLAY 0.978723 (-3350 3900);
DISPLAY INVISIBLE (-3350 3900);
WIRE 16 -1 (-7700 3725)(-7700 3825);
WIRE 16 -1 (-7675 5050)(-7675 5150);
WIRE 16 -1 (-5025 4700)(-5025 4650);
WIRE 16 -1 (-4625 4575)(-4625 4450);
WIRE 16 -1 (-4675 3725)(-4675 3625);
WIRE 16 -1 (-4925 4375)(-4925 4325);
WIRE 16 -1 (-5900 3550)(-5900 4025);
WIRE 16 -1 (-7525 4275)(-7525 4150);
WIRE 16 -1 (-7550 2950)(-7550 2825);
WIRE 16 -1 (-5750 3975)(-6500 3975);
FORCEPROP 0 LAST CDS_PHYS_NET_NAME IRQ_LPC_SERIRQ_ESPI_CS1_N
J 0
(-6210 4023);
PAINT MONO (-6210 4023);
DISPLAY INVISIBLE (-6210 4023);
FORCEPROP 2 LAST SIG_NAME PECI_PCH_B1
J 0
(-6385 3985);
DISPLAY 0.638298 (-6385 3985);
PAINT WHITE (-6385 3985);
WIRE 16 -1 (-6500 3300)(-6500 3975);
WIRE 16 -1 (-6975 3300)(-6500 3300);
WIRE 16 -1 (-9600 4625)(-8900 4625);
FORCEPROP 0 LAST CDS_PHYS_NET_NAME IRQ_LPC_SERIRQ_ESPI_CS1_N
J 0
(-9410 4673);
PAINT MONO (-9410 4673);
DISPLAY INVISIBLE (-9410 4673);
FORCEPROP 2 LAST SIG_NAME PECI_BMC
J 0
(-9460 4635);
DISPLAY 0.638298 (-9460 4635);
PAINT WHITE (-9460 4635);
WIRE 16 2175 (-7650 2850)(-7300 2850);
WIRE 16 2175 (-7300 3225)(-7300 2850);
WIRE 16 2175 (-7650 3225)(-7650 2850);
WIRE 16 2175 (-7650 3225)(-7300 3225);
WIRE 16 -1 (-5150 3975)(-5025 3975);
WIRE 16 -1 (-5025 2125)(-4375 2125);
WIRE 16 -1 (-5025 3975)(-5025 2125);
WIRE 16 -1 (-9625 2125)(-5025 2125);
FORCEPROP 0 LAST CDS_PHYS_NET_NAME IRQ_LPC_SERIRQ_ESPI_CS1_N
J 0
(-9435 2173);
PAINT MONO (-9435 2173);
DISPLAY INVISIBLE (-9435 2173);
FORCEPROP 2 LAST SIG_NAME PECI_CPU_GTL
J 0
(-9435 2135);
DISPLAY 0.638298 (-9435 2135);
PAINT WHITE (-9435 2135);
WIRE 16 -1 (-7700 3300)(-8700 3300);
FORCEPROP 0 LAST CDS_PHYS_NET_NAME IRQ_LPC_SERIRQ_ESPI_CS1_N
J 0
(-8235 3348);
PAINT MONO (-8235 3348);
DISPLAY INVISIBLE (-8235 3348);
FORCEPROP 2 LAST SIG_NAME PECI_PCH_R
J 0
(-8110 3310);
DISPLAY 0.638298 (-8110 3310);
PAINT WHITE (-8110 3310);
WIRE 16 -1 (-7700 3525)(-7700 3300);
WIRE 16 -1 (-7700 3300)(-7550 3300);
WIRE 16 -1 (-7550 3300)(-7175 3300);
WIRE 16 -1 (-7550 3150)(-7550 3300);
WIRE 16 2175 (-9125 4875)(-8300 4875);
WIRE 16 2175 (-8300 4875)(-8300 4500);
WIRE 16 2175 (-9125 4875)(-9125 4500);
WIRE 16 2175 (-9125 4500)(-8300 4500);
WIRE 16 2175 (-9025 3550)(-8200 3550);
WIRE 16 2175 (-8200 3550)(-8200 3175);
WIRE 16 2175 (-9025 3550)(-9025 3175);
WIRE 16 2175 (-9025 3175)(-8200 3175);
WIRE 16 -1 (-9625 3300)(-8900 3300);
FORCEPROP 0 LAST CDS_PHYS_NET_NAME IRQ_LPC_SERIRQ_ESPI_CS1_N
J 0
(-9435 3348);
PAINT MONO (-9435 3348);
DISPLAY INVISIBLE (-9435 3348);
FORCEPROP 2 LAST SIG_NAME PECI_PCH
J 0
(-9485 3310);
DISPLAY 0.638298 (-9485 3310);
PAINT WHITE (-9485 3310);
WIRE 16 -1 (-7675 4625)(-8700 4625);
FORCEPROP 0 LAST CDS_PHYS_NET_NAME IRQ_LPC_SERIRQ_ESPI_CS1_N
J 0
(-8235 4673);
PAINT MONO (-8235 4673);
DISPLAY INVISIBLE (-8235 4673);
FORCEPROP 2 LAST SIG_NAME PECI_BMC_R
J 0
(-8085 4635);
DISPLAY 0.638298 (-8085 4635);
PAINT WHITE (-8085 4635);
WIRE 16 -1 (-7675 4850)(-7675 4625);
WIRE 16 -1 (-7675 4625)(-7525 4625);
WIRE 16 -1 (-7525 4625)(-7150 4625);
WIRE 16 -1 (-7525 4475)(-7525 4625);
WIRE 16 2175 (-7625 4550)(-7150 4550);
WIRE 16 2175 (-7150 4550)(-7150 4175);
WIRE 16 2175 (-7625 4550)(-7625 4175);
WIRE 16 2175 (-7625 4175)(-7150 4175);
WIRE 16 -1 (-6950 4625)(-6500 4625);
WIRE 16 -1 (-6500 4625)(-6500 4075);
WIRE 16 -1 (-5750 4075)(-6500 4075);
FORCEPROP 0 LAST CDS_PHYS_NET_NAME IRQ_LPC_SERIRQ_ESPI_CS1_N
J 0
(-6210 4123);
PAINT MONO (-6210 4123);
DISPLAY INVISIBLE (-6210 4123);
FORCEPROP 2 LAST SIG_NAME PECI_BMC_B1
J 0
(-6385 4085);
DISPLAY 0.638298 (-6385 4085);
PAINT WHITE (-6385 4085);
WIRE 16 -1 (-5900 4025)(-5750 4025);
WIRE 16 -1 (-4175 2125)(-3250 2125);
FORCEPROP 2 LAST SIG_NAME PECI_BMC_ME
J 0
(-3712 2135);
DISPLAY 0.638298 (-3712 2135);
PAINT WHITE (-3712 2135);
WIRE 16 -1 (-5025 4025)(-5150 4025);
WIRE 16 -1 (-5025 4650)(-5025 4025);
WIRE 16 -1 (-4925 4650)(-5025 4650);
WIRE 16 -1 (-4925 4575)(-4925 4650);
WIRE 16 -1 (-4675 4075)(-5150 4075);
WIRE 16 -1 (-4675 3925)(-4675 4075);
WIRE 16 -1 (-4625 4075)(-4675 4075);
WIRE 16 -1 (-4625 4250)(-4625 4075);
WIRE 16 -1 (-3775 4075)(-4625 4075);
FORCEPROP 0 LAST CDS_PHYS_NET_NAME IRQ_LPC_SERIRQ_ESPI_CS1_N
J 0
(-4260 4123);
PAINT MONO (-4260 4123);
DISPLAY INVISIBLE (-4260 4123);
FORCEPROP 2 LAST SIG_NAME PECI_MUX_SEL_R
J 0
(-4510 4085);
DISPLAY 0.510638 (-4510 4085);
PAINT WHITE (-4510 4085);
WIRE 16 -1 (-3575 4075)(-2550 4075);
FORCEPROP 0 LAST CDS_PHYS_NET_NAME IRQ_LPC_SERIRQ_ESPI_CS1_N
J 0
(-2985 4123);
PAINT MONO (-2985 4123);
DISPLAY INVISIBLE (-2985 4123);
FORCEPROP 2 LAST SIG_NAME FM_PECI_MUX_SEL_N
J 0
(-3160 4085);
DISPLAY 0.510638 (-3160 4085);
PAINT WHITE (-3160 4085);
DOT 1 (-5025 2125);
DOT 1 (-5025 4650);
DOT 1 (-4625 4075);
DOT 1 (-4675 4075);
DOT 1 (-7550 3300);
DOT 1 (-7675 4625);
DOT 1 (-7525 4625);
DOT 1 (-7700 3300);
FORCENOTE
20211203 CHANGE R147,R148 TO 10K OHM
(-8350 2500) 0;
DISPLAY LEFT (-8350 2500);
DISPLAY 1.595745 (-8350 2500);
PAINT PINK (-8350 2500);
FORCENOTE
20211116 MODIFY FOR GT
(-8350 2600) 0;
DISPLAY LEFT (-8350 2600);
DISPLAY 1.595745 (-8350 2600);
PAINT PINK (-8350 2600);
QUIT
